(kicad_pcb
	(version 20260206)
	(generator "pcbnew")
	(generator_version "10.0")
	(general
		(thickness 1.6)
		(legacy_teardrops no)
	)
	(paper "A4")
	(title_block
		(title "Wiwynn_Tioga_Pass_MB.brd")
		(comment 1 "Tioga Pass / footprint 190 of 4770 (U2D1), pads 2911-2977 of 3647")
	)
	(layers
		(0 "F.Cu" signal "TOP")
		(4 "In1.Cu" signal "L2GND")
		(6 "In2.Cu" signal "L3")
		(8 "In3.Cu" signal "L4GND")
		(10 "In4.Cu" signal "L5")
		(12 "In5.Cu" signal "L6GND")
		(14 "In6.Cu" signal "L7VCC")
		(16 "In7.Cu" signal "L8VCC")
		(18 "In8.Cu" signal "L9GND")
		(20 "In9.Cu" signal "L10")
		(22 "In10.Cu" signal "L11GND")
		(24 "In11.Cu" signal "L12")
		(26 "In12.Cu" signal "L13GND")
		(2 "B.Cu" signal "BOTTOM")
		(9 "F.Adhes" user "F.Adhesive")
		(11 "B.Adhes" user "B.Adhesive")
		(13 "F.Paste" user "Package Geometry/Pastemask Top")
		(15 "B.Paste" user "Package Geometry/Pastemask Bottom")
		(5 "F.SilkS" user "Ref Des/Silkscreen Top")
		(7 "B.SilkS" user "Ref Des/Silkscreen Bottom")
		(1 "F.Mask" user "Board Geometry/Soldermask Top")
		(3 "B.Mask" user "Board Geometry/Soldermask Bottom")
		(17 "Dwgs.User" user "User.Drawings")
		(19 "Cmts.User" user "User.Comments")
		(21 "Eco1.User" user "User.Eco1")
		(23 "Eco2.User" user "User.Eco2")
		(25 "Edge.Cuts" user "Board Geometry/Outline")
		(27 "Margin" user)
		(31 "F.CrtYd" user "Package Geometry/Place Bound Top")
		(29 "B.CrtYd" user "Package Geometry/Place Bound Bottom")
		(35 "F.Fab" user "Ref Des/Assembly Top")
		(33 "B.Fab" user "Ref Des/Assembly Bottom")
	)
	(footprint ""
		(layer "F.Cu")
		(at 104.99979 -76.550012 180)
		(property "Reference" "U2D1"
			(at 25.19299 30.484318 0)
			(unlocked yes)
			(layer "F.SilkS")
			(effects
				(font
					(size 0.7874 0.5842)
					(thickness 0.1524)
				)
			)
		)
		(property "Value" ""
			(at 0 0 180)
			(layer "F.Fab")
			(effects
				(font
					(size 1.27 1.27)
				)
			)
		)
		(duplicate_pad_numbers_are_jumpers no)
		(pad "EC44" smd circle
			(at 1.193546 23.617174)
			(size 0.508 0.508)
			(layers "F.Cu" "F.Mask" "F.Paste")
			(net "TP_CPU1_RSVD_13")
		)
		(pad "EC46" smd circle
			(at 2.910586 23.617174)
			(size 0.4318 0.4318)
			(layers "F.Cu" "F.Mask" "F.Paste")
			(net "PVDDQ_KLM")
		)
		(pad "EC48" smd circle
			(at 4.627626 23.617174)
			(size 0.4318 0.4318)
			(layers "F.Cu" "F.Mask" "F.Paste")
			(net "PVDDQ_KLM")
		)
		(pad "EC50" smd circle
			(at 6.344412 23.617174)
			(size 0.4318 0.4318)
			(layers "F.Cu" "F.Mask" "F.Paste")
			(net "PVDDQ_KLM")
		)
		(pad "EC52" smd circle
			(at 8.061452 23.617174)
			(size 0.4318 0.4318)
			(layers "F.Cu" "F.Mask" "F.Paste")
			(net "PVDDQ_KLM")
		)
		(pad "EC54" smd circle
			(at 9.778492 23.617174)
			(size 0.4318 0.4318)
			(layers "F.Cu" "F.Mask" "F.Paste")
			(net "PVDDQ_KLM")
		)
		(pad "EC56" smd circle
			(at 11.495532 23.617174)
			(size 0.4318 0.4318)
			(layers "F.Cu" "F.Mask" "F.Paste")
			(net "PVDDQ_KLM")
		)
		(pad "EC58" smd circle
			(at 13.212572 23.617174)
			(size 0.4318 0.4318)
			(layers "F.Cu" "F.Mask" "F.Paste")
			(net "PVDDQ_KLM")
		)
		(pad "EC60" smd circle
			(at 14.929612 23.617174)
			(size 0.4318 0.4318)
			(layers "F.Cu" "F.Mask" "F.Paste")
			(net "PVDDQ_KLM")
		)
		(pad "EC62" smd circle
			(at 16.646398 23.617174)
			(size 0.4318 0.4318)
			(layers "F.Cu" "F.Mask" "F.Paste")
			(net "PVDDQ_KLM")
		)
		(pad "EC70" smd circle
			(at 23.514558 23.617174)
			(size 0.4318 0.4318)
			(layers "F.Cu" "F.Mask" "F.Paste")
			(net "GND")
		)
		(pad "EC72" smd circle
			(at 25.231598 23.617174)
			(size 0.4318 0.4318)
			(layers "F.Cu" "F.Mask" "F.Paste")
			(net "GND")
		)
		(pad "EC74" smd circle
			(at 26.948384 23.617174)
			(size 0.4318 0.4318)
			(layers "F.Cu" "F.Mask" "F.Paste")
			(net "GND")
		)
		(pad "EC76" smd circle
			(at 28.665424 23.617174)
			(size 0.4318 0.4318)
			(layers "F.Cu" "F.Mask" "F.Paste")
			(net "GND")
		)
		(pad "EC78" smd circle
			(at 30.382464 23.617174)
			(size 0.4318 0.4318)
			(layers "F.Cu" "F.Mask" "F.Paste")
			(net "M_L_DQ<23>")
		)
		(pad "EC80" smd circle
			(at 32.099504 23.617174)
			(size 0.4318 0.4318)
			(layers "F.Cu" "F.Mask" "F.Paste")
			(net "M_L_DQ<17>")
		)
		(pad "EC82" smd custom
			(at 33.816544 23.617174 225)
			(size 0.10795 0.10795)
			(layers "F.Cu" "F.Mask" "F.Paste")
			(net "GND")
			(options
				(clearance outline)
				(anchor circle)
			)
			(primitives
				(gr_poly
					(pts
						(arc
							(start 0.2159 -0.0381)
							(mid 0 -0.254)
							(end -0.2159 -0.0381)
						)
						(arc
							(start -0.2159 0.0381)
							(mid 0 0.254)
							(end 0.2159 0.0381)
						)
					)
					(width 0)
					(fill yes)
				)
			)
		)
		(pad "EC84" smd custom
			(at 35.533584 23.617174 270)
			(size 0.10795 0.10795)
			(layers "F.Cu" "F.Mask" "F.Paste")
			(net "TP_CPU1_RSVD_12")
			(options
				(clearance outline)
				(anchor circle)
			)
			(primitives
				(gr_poly
					(pts
						(arc
							(start 0.2159 -0.0381)
							(mid 0 -0.254)
							(end -0.2159 -0.0381)
						)
						(arc
							(start -0.2159 0.0381)
							(mid 0 0.254)
							(end 0.2159 0.0381)
						)
					)
					(width 0)
					(fill yes)
				)
			)
		)
		(pad "ED5" smd custom
			(at -33.816544 25.912572 135)
			(size 0.10795 0.10795)
			(layers "F.Cu" "F.Mask" "F.Paste")
			(net "TP_CPU1_RSVD_10")
			(options
				(clearance outline)
				(anchor circle)
			)
			(primitives
				(gr_poly
					(pts
						(arc
							(start 0.2159 -0.0381)
							(mid 0 -0.254)
							(end -0.2159 -0.0381)
						)
						(arc
							(start -0.2159 0.0381)
							(mid 0 0.254)
							(end 0.2159 0.0381)
						)
					)
					(width 0)
					(fill yes)
				)
			)
		)
		(pad "ED7" smd custom
			(at -32.099504 25.912572 135)
			(size 0.10795 0.10795)
			(layers "F.Cu" "F.Mask" "F.Paste")
			(net "GND")
			(options
				(clearance outline)
				(anchor circle)
			)
			(primitives
				(gr_poly
					(pts
						(arc
							(start 0.2159 -0.0381)
							(mid 0 -0.254)
							(end -0.2159 -0.0381)
						)
						(arc
							(start -0.2159 0.0381)
							(mid 0 0.254)
							(end 0.2159 0.0381)
						)
					)
					(width 0)
					(fill yes)
				)
			)
		)
		(pad "ED9" smd circle
			(at -30.382464 25.912572)
			(size 0.4318 0.4318)
			(layers "F.Cu" "F.Mask" "F.Paste")
			(net "TP_P3E_CPU1_PE1_RSR3_TXN<15>")
		)
		(pad "ED11" smd circle
			(at -28.665424 25.912572)
			(size 0.4318 0.4318)
			(layers "F.Cu" "F.Mask" "F.Paste")
			(net "GND")
		)
		(pad "ED13" smd circle
			(at -26.948384 25.912572)
			(size 0.4318 0.4318)
			(layers "F.Cu" "F.Mask" "F.Paste")
			(net "P3E_CPU1_PE3_MP_TXP<1>")
		)
		(pad "ED15" smd circle
			(at -25.231598 25.912572)
			(size 0.4318 0.4318)
			(layers "F.Cu" "F.Mask" "F.Paste")
			(net "GND")
		)
		(pad "ED23" smd custom
			(at -18.363438 25.912572 120)
			(size 0.10795 0.10795)
			(layers "F.Cu" "F.Mask" "F.Paste")
			(net "GND")
			(options
				(clearance outline)
				(anchor circle)
			)
			(primitives
				(gr_poly
					(pts
						(arc
							(start 0.2159 -0.0381)
							(mid 0 -0.254)
							(end -0.2159 -0.0381)
						)
						(arc
							(start -0.2159 0.0381)
							(mid 0 0.254)
							(end 0.2159 0.0381)
						)
					)
					(width 0)
					(fill yes)
				)
			)
		)
		(pad "ED25" smd circle
			(at -16.646398 25.912572)
			(size 0.4318 0.4318)
			(layers "F.Cu" "F.Mask" "F.Paste")
			(net "M_L_DQ<55>")
		)
		(pad "ED27" smd circle
			(at -14.929612 25.912572)
			(size 0.4318 0.4318)
			(layers "F.Cu" "F.Mask" "F.Paste")
			(net "M_L_DQ<49>")
		)
		(pad "ED29" smd circle
			(at -13.212572 25.912572)
			(size 0.4318 0.4318)
			(layers "F.Cu" "F.Mask" "F.Paste")
			(net "GND")
		)
		(pad "ED31" smd circle
			(at -11.495532 25.912572)
			(size 0.4318 0.4318)
			(layers "F.Cu" "F.Mask" "F.Paste")
			(net "M_L_DQ<47>")
		)
		(pad "ED33" smd circle
			(at -9.778492 25.912572)
			(size 0.4318 0.4318)
			(layers "F.Cu" "F.Mask" "F.Paste")
			(net "M_L_DQ<41>")
		)
		(pad "ED35" smd circle
			(at -8.061452 25.912572)
			(size 0.4318 0.4318)
			(layers "F.Cu" "F.Mask" "F.Paste")
			(net "GND")
		)
		(pad "ED37" smd circle
			(at -6.344412 25.912572)
			(size 0.4318 0.4318)
			(layers "F.Cu" "F.Mask" "F.Paste")
			(net "M_K_DQ<39>")
		)
		(pad "ED39" smd circle
			(at -4.627626 25.912572)
			(size 0.4318 0.4318)
			(layers "F.Cu" "F.Mask" "F.Paste")
			(net "M_K_DQ<33>")
		)
		(pad "ED41" smd custom
			(at -2.910586 25.912572 225)
			(size 0.10795 0.10795)
			(layers "F.Cu" "F.Mask" "F.Paste")
			(net "GND")
			(options
				(clearance outline)
				(anchor circle)
			)
			(primitives
				(gr_poly
					(pts
						(arc
							(start 0.2159 -0.0381)
							(mid 0 -0.254)
							(end -0.2159 -0.0381)
						)
						(arc
							(start -0.2159 0.0381)
							(mid 0 0.254)
							(end 0.2159 0.0381)
						)
					)
					(width 0)
					(fill yes)
				)
			)
		)
		(pad "ED45" smd circle
			(at 2.052066 24.112474)
			(size 0.4318 0.4318)
			(layers "F.Cu" "F.Mask" "F.Paste")
			(net "TP_CPU1_RSVD_11")
		)
		(pad "ED47" smd circle
			(at 3.769106 24.112474)
			(size 0.4318 0.4318)
			(layers "F.Cu" "F.Mask" "F.Paste")
			(net "M_K_CS_N<2>")
		)
		(pad "ED49" smd circle
			(at 5.485892 24.112474)
			(size 0.4318 0.4318)
			(layers "F.Cu" "F.Mask" "F.Paste")
			(net "M_K_CS_N<1>")
		)
		(pad "ED51" smd circle
			(at 7.202932 24.112474)
			(size 0.4318 0.4318)
			(layers "F.Cu" "F.Mask" "F.Paste")
			(net "M_K_MA<14>")
		)
		(pad "ED53" smd circle
			(at 8.919972 24.112474)
			(size 0.4318 0.4318)
			(layers "F.Cu" "F.Mask" "F.Paste")
			(net "M_K_PAR")
		)
		(pad "ED55" smd circle
			(at 10.637012 24.112474)
			(size 0.4318 0.4318)
			(layers "F.Cu" "F.Mask" "F.Paste")
			(net "M_K_CLK_DN<0>")
		)
		(pad "ED57" smd circle
			(at 12.354052 24.112474)
			(size 0.4318 0.4318)
			(layers "F.Cu" "F.Mask" "F.Paste")
			(net "M_K_MA<1>")
		)
		(pad "ED59" smd circle
			(at 14.071092 24.112474)
			(size 0.4318 0.4318)
			(layers "F.Cu" "F.Mask" "F.Paste")
			(net "M_K_MA<4>")
		)
		(pad "ED61" smd circle
			(at 15.787878 24.112474)
			(size 0.4318 0.4318)
			(layers "F.Cu" "F.Mask" "F.Paste")
			(net "M_K_BG<0>")
		)
		(pad "ED63" smd custom
			(at 17.504918 24.112474 180)
			(size 0.10795 0.10795)
			(layers "F.Cu" "F.Mask" "F.Paste")
			(net "M_K_ALERT_N")
			(options
				(clearance outline)
				(anchor circle)
			)
			(primitives
				(gr_poly
					(pts
						(arc
							(start 0.2159 -0.0381)
							(mid 0 -0.254)
							(end -0.2159 -0.0381)
						)
						(arc
							(start -0.2159 0.0381)
							(mid 0 0.254)
							(end 0.2159 0.0381)
						)
					)
					(width 0)
					(fill yes)
				)
			)
		)
		(pad "ED69" smd custom
			(at 22.656038 24.112474 180)
			(size 0.10795 0.10795)
			(layers "F.Cu" "F.Mask" "F.Paste")
			(net "GND")
			(options
				(clearance outline)
				(anchor circle)
			)
			(primitives
				(gr_poly
					(pts
						(arc
							(start 0.2159 -0.0381)
							(mid 0 -0.254)
							(end -0.2159 -0.0381)
						)
						(arc
							(start -0.2159 0.0381)
							(mid 0 0.254)
							(end 0.2159 0.0381)
						)
					)
					(width 0)
					(fill yes)
				)
			)
		)
		(pad "ED71" smd circle
			(at 24.373078 24.112474)
			(size 0.4318 0.4318)
			(layers "F.Cu" "F.Mask" "F.Paste")
			(net "M_L_DQ<27>")
		)
		(pad "ED73" smd circle
			(at 26.090118 24.112474)
			(size 0.4318 0.4318)
			(layers "F.Cu" "F.Mask" "F.Paste")
			(net "M_L_DQS_DP<3>")
		)
		(pad "ED75" smd circle
			(at 27.806904 24.112474)
			(size 0.4318 0.4318)
			(layers "F.Cu" "F.Mask" "F.Paste")
			(net "M_L_DQ<24>")
		)
		(pad "ED77" smd circle
			(at 29.523944 24.112474)
			(size 0.4318 0.4318)
			(layers "F.Cu" "F.Mask" "F.Paste")
			(net "GND")
		)
		(pad "ED79" smd circle
			(at 31.240984 24.112474)
			(size 0.4318 0.4318)
			(layers "F.Cu" "F.Mask" "F.Paste")
			(net "M_L_DQS_DN<2>")
		)
		(pad "ED81" smd custom
			(at 32.958024 24.112474 225)
			(size 0.10795 0.10795)
			(layers "F.Cu" "F.Mask" "F.Paste")
			(net "GND")
			(options
				(clearance outline)
				(anchor circle)
			)
			(primitives
				(gr_poly
					(pts
						(arc
							(start 0.2159 -0.0381)
							(mid 0 -0.254)
							(end -0.2159 -0.0381)
						)
						(arc
							(start -0.2159 0.0381)
							(mid 0 0.254)
							(end 0.2159 0.0381)
						)
					)
					(width 0)
					(fill yes)
				)
			)
		)
		(pad "ED83" smd custom
			(at 34.675064 24.112474 270)
			(size 0.10795 0.10795)
			(layers "F.Cu" "F.Mask" "F.Paste")
			(net "TP_CPU1_RSVD_9")
			(options
				(clearance outline)
				(anchor circle)
			)
			(primitives
				(gr_poly
					(pts
						(arc
							(start 0.2159 -0.0381)
							(mid 0 -0.254)
							(end -0.2159 -0.0381)
						)
						(arc
							(start -0.2159 0.0381)
							(mid 0 0.254)
							(end 0.2159 0.0381)
						)
					)
					(width 0)
					(fill yes)
				)
			)
		)
		(pad "EE6" smd custom
			(at -32.958024 26.408126 135)
			(size 0.10795 0.10795)
			(layers "F.Cu" "F.Mask" "F.Paste")
			(net "TP_CPU1_RSVD_6")
			(options
				(clearance outline)
				(anchor circle)
			)
			(primitives
				(gr_poly
					(pts
						(arc
							(start 0.2159 -0.0381)
							(mid 0 -0.254)
							(end -0.2159 -0.0381)
						)
						(arc
							(start -0.2159 0.0381)
							(mid 0 0.254)
							(end 0.2159 0.0381)
						)
					)
					(width 0)
					(fill yes)
				)
			)
		)
		(pad "EE8" smd custom
			(at -31.240984 26.408126 135)
			(size 0.10795 0.10795)
			(layers "F.Cu" "F.Mask" "F.Paste")
			(net "GND")
			(options
				(clearance outline)
				(anchor circle)
			)
			(primitives
				(gr_poly
					(pts
						(arc
							(start 0.2159 -0.0381)
							(mid 0 -0.254)
							(end -0.2159 -0.0381)
						)
						(arc
							(start -0.2159 0.0381)
							(mid 0 0.254)
							(end 0.2159 0.0381)
						)
					)
					(width 0)
					(fill yes)
				)
			)
		)
		(pad "EE10" smd custom
			(at -29.523944 26.408126 180)
			(size 0.10795 0.10795)
			(layers "F.Cu" "F.Mask" "F.Paste")
			(net "PVCCIO_CPU1")
			(options
				(clearance outline)
				(anchor circle)
			)
			(primitives
				(gr_poly
					(pts
						(arc
							(start 0.2159 -0.0381)
							(mid 0 -0.254)
							(end -0.2159 -0.0381)
						)
						(arc
							(start -0.2159 0.0381)
							(mid 0 0.254)
							(end 0.2159 0.0381)
						)
					)
					(width 0)
					(fill yes)
				)
			)
		)
		(pad "EE12" smd custom
			(at -27.806904 26.408126 180)
			(size 0.10795 0.10795)
			(layers "F.Cu" "F.Mask" "F.Paste")
			(net "P3E_CPU1_PE3_MP_TXN<1>")
			(options
				(clearance outline)
				(anchor circle)
			)
			(primitives
				(gr_poly
					(pts
						(arc
							(start 0.2159 -0.0381)
							(mid 0 -0.254)
							(end -0.2159 -0.0381)
						)
						(arc
							(start -0.2159 0.0381)
							(mid 0 0.254)
							(end 0.2159 0.0381)
						)
					)
					(width 0)
					(fill yes)
				)
			)
		)
		(pad "EE14" smd custom
			(at -26.090118 26.408126 180)
			(size 0.10795 0.10795)
			(layers "F.Cu" "F.Mask" "F.Paste")
			(net "P3E_CPU1_PE3_MP_TXN<0>")
			(options
				(clearance outline)
				(anchor circle)
			)
			(primitives
				(gr_poly
					(pts
						(arc
							(start 0.2159 -0.0381)
							(mid 0 -0.254)
							(end -0.2159 -0.0381)
						)
						(arc
							(start -0.2159 0.0381)
							(mid 0 0.254)
							(end 0.2159 0.0381)
						)
					)
					(width 0)
					(fill yes)
				)
			)
		)
		(pad "EE16" smd custom
			(at -24.373078 26.408126 180)
			(size 0.10795 0.10795)
			(layers "F.Cu" "F.Mask" "F.Paste")
			(net "TP_CPU1_RSVD_8")
			(options
				(clearance outline)
				(anchor circle)
			)
			(primitives
				(gr_poly
					(pts
						(arc
							(start 0.2159 -0.0381)
							(mid 0 -0.254)
							(end -0.2159 -0.0381)
						)
						(arc
							(start -0.2159 0.0381)
							(mid 0 0.254)
							(end 0.2159 0.0381)
						)
					)
					(width 0)
					(fill yes)
				)
			)
		)
		(pad "EE24" smd custom
			(at -17.504918 26.408126 120)
			(size 0.10795 0.10795)
			(layers "F.Cu" "F.Mask" "F.Paste")
			(net "GND")
			(options
				(clearance outline)
				(anchor circle)
			)
			(primitives
				(gr_poly
					(pts
						(arc
							(start 0.2159 -0.0381)
							(mid 0 -0.254)
							(end -0.2159 -0.0381)
						)
						(arc
							(start -0.2159 0.0381)
							(mid 0 0.254)
							(end 0.2159 0.0381)
						)
					)
					(width 0)
					(fill yes)
				)
			)
		)
		(pad "EE26" smd custom
			(at -15.787878 26.408126 180)
			(size 0.10795 0.10795)
			(layers "F.Cu" "F.Mask" "F.Paste")
			(net "M_L_DQS_DN<6>")
			(options
				(clearance outline)
				(anchor circle)
			)
			(primitives
				(gr_poly
					(pts
						(arc
							(start 0.2159 -0.0381)
							(mid 0 -0.254)
							(end -0.2159 -0.0381)
						)
						(arc
							(start -0.2159 0.0381)
							(mid 0 0.254)
							(end 0.2159 0.0381)
						)
					)
					(width 0)
					(fill yes)
				)
			)
		)
		(pad "EE28" smd custom
			(at -14.071092 26.408126 180)
			(size 0.10795 0.10795)
			(layers "F.Cu" "F.Mask" "F.Paste")
			(net "GND")
			(options
				(clearance outline)
				(anchor circle)
			)
			(primitives
				(gr_poly
					(pts
						(arc
							(start 0.2159 -0.0381)
							(mid 0 -0.254)
							(end -0.2159 -0.0381)
						)
						(arc
							(start -0.2159 0.0381)
							(mid 0 0.254)
							(end 0.2159 0.0381)
						)
					)
					(width 0)
					(fill yes)
				)
			)
		)
		(pad "EE30" smd custom
			(at -12.354052 26.408126 180)
			(size 0.10795 0.10795)
			(layers "F.Cu" "F.Mask" "F.Paste")
			(net "GND")
			(options
				(clearance outline)
				(anchor circle)
			)
			(primitives
				(gr_poly
					(pts
						(arc
							(start 0.2159 -0.0381)
							(mid 0 -0.254)
							(end -0.2159 -0.0381)
						)
						(arc
							(start -0.2159 0.0381)
							(mid 0 0.254)
							(end 0.2159 0.0381)
						)
					)
					(width 0)
					(fill yes)
				)
			)
		)
		(pad "EE32" smd custom
			(at -10.637012 26.408126 180)
			(size 0.10795 0.10795)
			(layers "F.Cu" "F.Mask" "F.Paste")
			(net "M_L_DQS_DN<5>")
			(options
				(clearance outline)
				(anchor circle)
			)
			(primitives
				(gr_poly
					(pts
						(arc
							(start 0.2159 -0.0381)
							(mid 0 -0.254)
							(end -0.2159 -0.0381)
						)
						(arc
							(start -0.2159 0.0381)
							(mid 0 0.254)
							(end 0.2159 0.0381)
						)
					)
					(width 0)
					(fill yes)
				)
			)
		)
		(pad "EE34" smd custom
			(at -8.919972 26.408126 180)
			(size 0.10795 0.10795)
			(layers "F.Cu" "F.Mask" "F.Paste")
			(net "GND")
			(options
				(clearance outline)
				(anchor circle)
			)
			(primitives
				(gr_poly
					(pts
						(arc
							(start 0.2159 -0.0381)
							(mid 0 -0.254)
							(end -0.2159 -0.0381)
						)
						(arc
							(start -0.2159 0.0381)
							(mid 0 0.254)
							(end 0.2159 0.0381)
						)
					)
					(width 0)
					(fill yes)
				)
			)
		)
		(pad "EE36" smd custom
			(at -7.202932 26.408126 180)
			(size 0.10795 0.10795)
			(layers "F.Cu" "F.Mask" "F.Paste")
			(net "GND")
			(options
				(clearance outline)
				(anchor circle)
			)
			(primitives
				(gr_poly
					(pts
						(arc
							(start 0.2159 -0.0381)
							(mid 0 -0.254)
							(end -0.2159 -0.0381)
						)
						(arc
							(start -0.2159 0.0381)
							(mid 0 0.254)
							(end 0.2159 0.0381)
						)
					)
					(width 0)
					(fill yes)
				)
			)
		)
		(pad "EE38" smd custom
			(at -5.485892 26.408126 180)
			(size 0.10795 0.10795)
			(layers "F.Cu" "F.Mask" "F.Paste")
			(net "M_K_DQS_DN<4>")
			(options
				(clearance outline)
				(anchor circle)
			)
			(primitives
				(gr_poly
					(pts
						(arc
							(start 0.2159 -0.0381)
							(mid 0 -0.254)
							(end -0.2159 -0.0381)
						)
						(arc
							(start -0.2159 0.0381)
							(mid 0 0.254)
							(end 0.2159 0.0381)
						)
					)
					(width 0)
					(fill yes)
				)
			)
		)
		(pad "EE40" smd custom
			(at -3.769106 26.408126 225)
			(size 0.10795 0.10795)
			(layers "F.Cu" "F.Mask" "F.Paste")
			(net "GND")
			(options
				(clearance outline)
				(anchor circle)
			)
			(primitives
				(gr_poly
					(pts
						(arc
							(start 0.2159 -0.0381)
							(mid 0 -0.254)
							(end -0.2159 -0.0381)
						)
						(arc
							(start -0.2159 0.0381)
							(mid 0 0.254)
							(end 0.2159 0.0381)
						)
					)
					(width 0)
					(fill yes)
				)
			)
		)
	)
)
